(kicad_pcb
	(version 20260206)
	(generator "pcbnew")
	(generator_version "10.0")
	(general
		(thickness 1.6)
		(legacy_teardrops no)
	)
	(paper "A4")
	(title_block
		(title "04192023_DAF0TMB3IC0_F0TG_MB_C_brd_V02_OCP.brd")
		(comment 1 "Grand Teton / footprints 7799-7804 of 8354")
	)
	(layers
		(0 "F.Cu" signal "TOP")
		(4 "In1.Cu" signal "GND")
		(6 "In2.Cu" signal "IN1")
		(8 "In3.Cu" signal "GND1")
		(10 "In4.Cu" signal "IN2")
		(12 "In5.Cu" signal "GND2")
		(14 "In6.Cu" signal "IN3")
		(16 "In7.Cu" signal "GND3")
		(18 "In8.Cu" signal "VCC")
		(20 "In9.Cu" signal "VCC1")
		(22 "In10.Cu" signal "GND4")
		(24 "In11.Cu" signal "IN4")
		(26 "In12.Cu" signal "GND5")
		(28 "In13.Cu" signal "IN5")
		(30 "In14.Cu" signal "GND6")
		(32 "In15.Cu" signal "IN6")
		(34 "In16.Cu" signal "GND7")
		(2 "B.Cu" signal "BOTTOM")
		(9 "F.Adhes" user "F.Adhesive")
		(11 "B.Adhes" user "B.Adhesive")
		(13 "F.Paste" user "Package Geometry/Pastemask Top")
		(15 "B.Paste" user "Package Geometry/Pastemask Bottom")
		(5 "F.SilkS" user "Ref Des/Silkscreen Top")
		(7 "B.SilkS" user "Ref Des/Silkscreen Bottom")
		(1 "F.Mask" user "Board Geometry/Soldermask Top")
		(3 "B.Mask" user "Board Geometry/Soldermask Bottom")
		(17 "Dwgs.User" user "User.Drawings")
		(19 "Cmts.User" user "User.Comments")
		(21 "Eco1.User" user "User.Eco1")
		(23 "Eco2.User" user "User.Eco2")
		(25 "Edge.Cuts" user "Board Geometry/Outline")
		(27 "Margin" user)
		(31 "F.CrtYd" user "Package Geometry/Place Bound Top")
		(29 "B.CrtYd" user "Package Geometry/Place Bound Bottom")
		(35 "F.Fab" user "Ref Des/Assembly Top")
		(33 "B.Fab" user "Ref Des/Assembly Bottom")
	)
	(footprint ""
		(layer "B.Cu")
		(at 424.646598 -362.378244)
		(property "Reference" "PR113"
			(at 0 0 0)
			(layer "B.SilkS")
			(hide yes)
			(effects
				(font
					(size 1.27 1.27)
				)
				(justify mirror)
			)
		)
		(property "Value" ""
			(at 0 0 0)
			(layer "B.Fab")
			(effects
				(font
					(size 1.27 1.27)
				)
				(justify mirror)
			)
		)
		(duplicate_pad_numbers_are_jumpers no)
		(fp_line
			(start -0.7874 -0.4064)
			(end -0.7874 0.4064)
			(stroke
				(width 0.1524)
				(type default)
			)
			(layer "B.SilkS")
		)
		(fp_line
			(start -0.7874 0.4064)
			(end 0.7874 0.4064)
			(stroke
				(width 0.1524)
				(type default)
			)
			(layer "B.SilkS")
		)
		(fp_line
			(start 0.7874 -0.4064)
			(end -0.7874 -0.4064)
			(stroke
				(width 0.1524)
				(type default)
			)
			(layer "B.SilkS")
		)
		(fp_line
			(start 0.7874 0.4064)
			(end 0.7874 -0.4064)
			(stroke
				(width 0.1524)
				(type default)
			)
			(layer "B.SilkS")
		)
		(fp_line
			(start -0.67945 -0.3048)
			(end -0.67945 0.3048)
			(stroke
				(width 0.1)
				(type default)
			)
			(layer "B.Fab")
		)
		(fp_line
			(start -0.67945 0.3048)
			(end -0.120396 0.3048)
			(stroke
				(width 0.1)
				(type default)
			)
			(layer "B.Fab")
		)
		(fp_line
			(start -0.12065 -0.3048)
			(end -0.67945 -0.3048)
			(stroke
				(width 0.1)
				(type default)
			)
			(layer "B.Fab")
		)
		(fp_line
			(start -0.12065 -0.2794)
			(end -0.12065 -0.3048)
			(stroke
				(width 0.1)
				(type default)
			)
			(layer "B.Fab")
		)
		(fp_line
			(start -0.120396 0.2794)
			(end 0.12065 0.2794)
			(stroke
				(width 0.1)
				(type default)
			)
			(layer "B.Fab")
		)
		(fp_line
			(start -0.120396 0.3048)
			(end -0.120396 0.2794)
			(stroke
				(width 0.1)
				(type default)
			)
			(layer "B.Fab")
		)
		(fp_line
			(start 0.12065 -0.305054)
			(end 0.12065 -0.2794)
			(stroke
				(width 0.1)
				(type default)
			)
			(layer "B.Fab")
		)
		(fp_line
			(start 0.12065 -0.2794)
			(end -0.12065 -0.2794)
			(stroke
				(width 0.1)
				(type default)
			)
			(layer "B.Fab")
		)
		(fp_line
			(start 0.12065 0.2794)
			(end 0.12065 0.3048)
			(stroke
				(width 0.1)
				(type default)
			)
			(layer "B.Fab")
		)
		(fp_line
			(start 0.12065 0.3048)
			(end 0.67945 0.3048)
			(stroke
				(width 0.1)
				(type default)
			)
			(layer "B.Fab")
		)
		(fp_line
			(start 0.67945 -0.305054)
			(end 0.12065 -0.305054)
			(stroke
				(width 0.1)
				(type default)
			)
			(layer "B.Fab")
		)
		(fp_line
			(start 0.67945 0.3048)
			(end 0.67945 -0.305054)
			(stroke
				(width 0.1)
				(type default)
			)
			(layer "B.Fab")
		)
		(pad "1" smd circle
			(at 0.40005 0 180)
			(size 0 0)
			(layers "B.Cu" "B.Mask" "B.Paste")
			(net "P5V_AUX")
		)
		(pad "2" smd circle
			(at -0.40005 0 180)
			(size 0 0)
			(layers "B.Cu" "B.Mask" "B.Paste")
			(net "PVDD11_S3_P0_VMON")
		)
	)
	(footprint ""
		(layer "B.Cu")
		(at 342.498934 -301.911258 -90)
		(property "Reference" "R4304"
			(at 0 0 90)
			(layer "B.SilkS")
			(hide yes)
			(effects
				(font
					(size 1.27 1.27)
				)
				(justify mirror)
			)
		)
		(property "Value" ""
			(at 0 0 90)
			(layer "B.Fab")
			(effects
				(font
					(size 1.27 1.27)
				)
				(justify mirror)
			)
		)
		(duplicate_pad_numbers_are_jumpers no)
		(fp_line
			(start -0.7874 0.4064)
			(end 0.7874 0.4064)
			(stroke
				(width 0.1524)
				(type default)
			)
			(layer "B.SilkS")
		)
		(fp_line
			(start 0.7874 0.4064)
			(end 0.7874 0.056134)
			(stroke
				(width 0.1524)
				(type default)
			)
			(layer "B.SilkS")
		)
		(fp_line
			(start -0.7874 0.056134)
			(end -0.7874 0.4064)
			(stroke
				(width 0.1524)
				(type default)
			)
			(layer "B.SilkS")
		)
		(fp_line
			(start 0.311658 -0.4064)
			(end -0.374142 -0.4064)
			(stroke
				(width 0.1524)
				(type default)
			)
			(layer "B.SilkS")
		)
		(fp_line
			(start -0.67945 0.3048)
			(end -0.120396 0.3048)
			(stroke
				(width 0.1)
				(type default)
			)
			(layer "B.Fab")
		)
		(fp_line
			(start -0.120396 0.3048)
			(end -0.120396 0.2794)
			(stroke
				(width 0.1)
				(type default)
			)
			(layer "B.Fab")
		)
		(fp_line
			(start 0.12065 0.3048)
			(end 0.67945 0.3048)
			(stroke
				(width 0.1)
				(type default)
			)
			(layer "B.Fab")
		)
		(fp_line
			(start 0.67945 0.3048)
			(end 0.67945 -0.305054)
			(stroke
				(width 0.1)
				(type default)
			)
			(layer "B.Fab")
		)
		(fp_line
			(start -0.120396 0.2794)
			(end 0.12065 0.2794)
			(stroke
				(width 0.1)
				(type default)
			)
			(layer "B.Fab")
		)
		(fp_line
			(start 0.12065 0.2794)
			(end 0.12065 0.3048)
			(stroke
				(width 0.1)
				(type default)
			)
			(layer "B.Fab")
		)
		(fp_line
			(start -0.12065 -0.2794)
			(end -0.12065 -0.3048)
			(stroke
				(width 0.1)
				(type default)
			)
			(layer "B.Fab")
		)
		(fp_line
			(start 0.12065 -0.2794)
			(end -0.12065 -0.2794)
			(stroke
				(width 0.1)
				(type default)
			)
			(layer "B.Fab")
		)
		(fp_line
			(start -0.67945 -0.3048)
			(end -0.67945 0.3048)
			(stroke
				(width 0.1)
				(type default)
			)
			(layer "B.Fab")
		)
		(fp_line
			(start -0.12065 -0.3048)
			(end -0.67945 -0.3048)
			(stroke
				(width 0.1)
				(type default)
			)
			(layer "B.Fab")
		)
		(fp_line
			(start 0.12065 -0.305054)
			(end 0.12065 -0.2794)
			(stroke
				(width 0.1)
				(type default)
			)
			(layer "B.Fab")
		)
		(fp_line
			(start 0.67945 -0.305054)
			(end 0.12065 -0.305054)
			(stroke
				(width 0.1)
				(type default)
			)
			(layer "B.Fab")
		)
		(pad "1" smd circle
			(at 0.40005 0 90)
			(size 0 0)
			(layers "B.Cu" "B.Mask" "B.Paste")
			(net "CLK_100M_CPU0_CLK12_R_DN")
		)
		(pad "2" smd circle
			(at -0.40005 0 90)
			(size 0 0)
			(layers "B.Cu" "B.Mask" "B.Paste")
			(net "CLK_100M_CPU0_CLK12_DN")
		)
	)
	(footprint ""
		(layer "B.Cu")
		(at 177.443638 -13.762228 90)
		(property "Reference" "R4506"
			(at 0 0 90)
			(layer "B.SilkS")
			(hide yes)
			(effects
				(font
					(size 1.27 1.27)
				)
				(justify mirror)
			)
		)
		(property "Value" ""
			(at 0 0 90)
			(layer "B.Fab")
			(effects
				(font
					(size 1.27 1.27)
				)
				(justify mirror)
			)
		)
		(duplicate_pad_numbers_are_jumpers no)
		(fp_line
			(start 0.7874 -0.4064)
			(end -0.7874 -0.4064)
			(stroke
				(width 0.1524)
				(type default)
			)
			(layer "B.SilkS")
		)
		(fp_line
			(start -0.7874 -0.4064)
			(end -0.7874 0.4064)
			(stroke
				(width 0.1524)
				(type default)
			)
			(layer "B.SilkS")
		)
		(fp_line
			(start 0.7874 0.4064)
			(end 0.7874 -0.4064)
			(stroke
				(width 0.1524)
				(type default)
			)
			(layer "B.SilkS")
		)
		(fp_line
			(start -0.7874 0.4064)
			(end 0.7874 0.4064)
			(stroke
				(width 0.1524)
				(type default)
			)
			(layer "B.SilkS")
		)
		(fp_line
			(start 0.67945 -0.305054)
			(end 0.12065 -0.305054)
			(stroke
				(width 0.1)
				(type default)
			)
			(layer "B.Fab")
		)
		(fp_line
			(start 0.12065 -0.305054)
			(end 0.12065 -0.2794)
			(stroke
				(width 0.1)
				(type default)
			)
			(layer "B.Fab")
		)
		(fp_line
			(start -0.12065 -0.3048)
			(end -0.67945 -0.3048)
			(stroke
				(width 0.1)
				(type default)
			)
			(layer "B.Fab")
		)
		(fp_line
			(start -0.67945 -0.3048)
			(end -0.67945 0.3048)
			(stroke
				(width 0.1)
				(type default)
			)
			(layer "B.Fab")
		)
		(fp_line
			(start 0.12065 -0.2794)
			(end -0.12065 -0.2794)
			(stroke
				(width 0.1)
				(type default)
			)
			(layer "B.Fab")
		)
		(fp_line
			(start -0.12065 -0.2794)
			(end -0.12065 -0.3048)
			(stroke
				(width 0.1)
				(type default)
			)
			(layer "B.Fab")
		)
		(fp_line
			(start 0.12065 0.2794)
			(end 0.12065 0.3048)
			(stroke
				(width 0.1)
				(type default)
			)
			(layer "B.Fab")
		)
		(fp_line
			(start -0.120396 0.2794)
			(end 0.12065 0.2794)
			(stroke
				(width 0.1)
				(type default)
			)
			(layer "B.Fab")
		)
		(fp_line
			(start 0.67945 0.3048)
			(end 0.67945 -0.305054)
			(stroke
				(width 0.1)
				(type default)
			)
			(layer "B.Fab")
		)
		(fp_line
			(start 0.12065 0.3048)
			(end 0.67945 0.3048)
			(stroke
				(width 0.1)
				(type default)
			)
			(layer "B.Fab")
		)
		(fp_line
			(start -0.120396 0.3048)
			(end -0.120396 0.2794)
			(stroke
				(width 0.1)
				(type default)
			)
			(layer "B.Fab")
		)
		(fp_line
			(start -0.67945 0.3048)
			(end -0.120396 0.3048)
			(stroke
				(width 0.1)
				(type default)
			)
			(layer "B.Fab")
		)
		(pad "1" smd circle
			(at 0.40005 0 270)
			(size 0 0)
			(layers "B.Cu" "B.Mask" "B.Paste")
			(net "SMB_CPU0_CPU1_SEC_SCL")
		)
		(pad "2" smd circle
			(at -0.40005 0 270)
			(size 0 0)
			(layers "B.Cu" "B.Mask" "B.Paste")
			(net "SMB_CPU0_CPU1_SEC_SCL_R")
		)
	)
	(footprint ""
		(layer "B.Cu")
		(at 14.340332 -383.53873 -90)
		(property "Reference" "PC6813"
			(at -3.17627 3.191002 270)
			(unlocked yes)
			(layer "B.SilkS")
			(effects
				(font
					(size 0.7874 0.5842)
					(thickness 0.1524)
				)
				(justify left mirror)
			)
		)
		(property "Value" ""
			(at 0 0 90)
			(layer "B.Fab")
			(effects
				(font
					(size 1.27 1.27)
				)
				(justify mirror)
			)
		)
		(duplicate_pad_numbers_are_jumpers no)
		(fp_line
			(start 4.83108 2.150364)
			(end 4.447794 2.149348)
			(stroke
				(width 0.1524)
				(type default)
			)
			(layer "B.SilkS")
		)
		(fp_line
			(start -4.53898 2.15011)
			(end 4.53898 2.15011)
			(stroke
				(width 0.1524)
				(type default)
			)
			(layer "B.SilkS")
		)
		(fp_line
			(start 4.53898 2.15011)
			(end 4.53898 -2.15011)
			(stroke
				(width 0.1524)
				(type default)
			)
			(layer "B.SilkS")
		)
		(fp_line
			(start -4.53898 -2.15011)
			(end -4.53898 2.15011)
			(stroke
				(width 0.1524)
				(type default)
			)
			(layer "B.SilkS")
		)
		(fp_line
			(start 4.53898 -2.15011)
			(end -4.53898 -2.15011)
			(stroke
				(width 0.1524)
				(type default)
			)
			(layer "B.SilkS")
		)
		(fp_line
			(start 4.53898 -2.150618)
			(end 4.539742 2.152142)
			(stroke
				(width 0.1524)
				(type default)
			)
			(layer "B.SilkS")
		)
		(fp_line
			(start 4.69138 -2.150618)
			(end 4.692396 2.161032)
			(stroke
				(width 0.1524)
				(type default)
			)
			(layer "B.SilkS")
		)
		(fp_line
			(start 4.84378 -2.150618)
			(end 4.842256 2.163064)
			(stroke
				(width 0.1524)
				(type default)
			)
			(layer "B.SilkS")
		)
		(fp_line
			(start 4.84378 -2.150618)
			(end 4.53898 -2.150618)
			(stroke
				(width 0.1524)
				(type default)
			)
			(layer "B.SilkS")
		)
		(fp_line
			(start -3.64998 2.15011)
			(end 3.64998 2.15011)
			(stroke
				(width 0.1)
				(type default)
			)
			(layer "B.Fab")
		)
		(fp_line
			(start 3.64998 2.15011)
			(end 3.64998 -2.15011)
			(stroke
				(width 0.1)
				(type default)
			)
			(layer "B.Fab")
		)
		(fp_line
			(start -3.64998 -2.15011)
			(end -3.64998 2.15011)
			(stroke
				(width 0.1)
				(type default)
			)
			(layer "B.Fab")
		)
		(fp_line
			(start 3.64998 -2.15011)
			(end -3.64998 -2.15011)
			(stroke
				(width 0.1)
				(type default)
			)
			(layer "B.Fab")
		)
		(fp_text user "-"
			(at -4.535678 -1.371346 270)
			(unlocked yes)
			(layer "B.SilkS")
			(effects
				(font
					(size 1.905 1.4224)
					(thickness 0.1524)
				)
				(justify left mirror)
			)
		)
		(fp_text user "+"
			(at 6.222492 -1.50114 270)
			(unlocked yes)
			(layer "B.SilkS")
			(effects
				(font
					(size 1.905 1.4224)
					(thickness 0.1524)
				)
				(justify left mirror)
			)
		)
		(fp_text user "-"
			(at -4.313174 -0.094488 270)
			(unlocked yes)
			(layer "B.Fab")
			(effects
				(font
					(size 1.905 1.4224)
					(thickness 0.1524)
				)
				(justify left mirror)
			)
		)
		(fp_text user "+"
			(at 6.214872 -0.337058 270)
			(unlocked yes)
			(layer "B.Fab")
			(effects
				(font
					(size 1.905 1.4224)
					(thickness 0.1524)
				)
				(justify left mirror)
			)
		)
		(pad "1" smd rect
			(at 3.199892 0 90)
			(size 2.413 2.8194)
			(layers "B.Cu" "B.Mask" "B.Paste")
			(net "P0V9_CPU1_RT_2D")
		)
		(pad "2" smd rect
			(at -3.199892 0 90)
			(size 2.413 2.8194)
			(layers "B.Cu" "B.Mask" "B.Paste")
			(net "GND")
		)
	)
	(footprint ""
		(layer "B.Cu")
		(at 113.705386 -253.432564)
		(property "Reference" "C2284"
			(at 0 0 0)
			(layer "B.SilkS")
			(hide yes)
			(effects
				(font
					(size 1.27 1.27)
				)
				(justify mirror)
			)
		)
		(property "Value" ""
			(at 0 0 0)
			(layer "B.Fab")
			(effects
				(font
					(size 1.27 1.27)
				)
				(justify mirror)
			)
		)
		(duplicate_pad_numbers_are_jumpers no)
		(fp_line
			(start -0.7874 -0.4064)
			(end -0.7874 0.4064)
			(stroke
				(width 0.1524)
				(type default)
			)
			(layer "B.SilkS")
		)
		(fp_line
			(start -0.7874 0.4064)
			(end 0.7874 0.4064)
			(stroke
				(width 0.1524)
				(type default)
			)
			(layer "B.SilkS")
		)
		(fp_line
			(start 0.7874 -0.4064)
			(end -0.7874 -0.4064)
			(stroke
				(width 0.1524)
				(type default)
			)
			(layer "B.SilkS")
		)
		(fp_line
			(start 0.7874 0.4064)
			(end 0.7874 -0.4064)
			(stroke
				(width 0.1524)
				(type default)
			)
			(layer "B.SilkS")
		)
		(fp_line
			(start -0.67945 -0.3048)
			(end -0.67945 0.3048)
			(stroke
				(width 0.1)
				(type default)
			)
			(layer "B.Fab")
		)
		(fp_line
			(start -0.67945 0.3048)
			(end -0.120396 0.3048)
			(stroke
				(width 0.1)
				(type default)
			)
			(layer "B.Fab")
		)
		(fp_line
			(start -0.12065 -0.3048)
			(end -0.67945 -0.3048)
			(stroke
				(width 0.1)
				(type default)
			)
			(layer "B.Fab")
		)
		(fp_line
			(start -0.12065 -0.2794)
			(end -0.12065 -0.3048)
			(stroke
				(width 0.1)
				(type default)
			)
			(layer "B.Fab")
		)
		(fp_line
			(start -0.120396 0.2794)
			(end 0.12065 0.2794)
			(stroke
				(width 0.1)
				(type default)
			)
			(layer "B.Fab")
		)
		(fp_line
			(start -0.120396 0.3048)
			(end -0.120396 0.2794)
			(stroke
				(width 0.1)
				(type default)
			)
			(layer "B.Fab")
		)
		(fp_line
			(start 0.12065 -0.305054)
			(end 0.12065 -0.2794)
			(stroke
				(width 0.1)
				(type default)
			)
			(layer "B.Fab")
		)
		(fp_line
			(start 0.12065 -0.2794)
			(end -0.12065 -0.2794)
			(stroke
				(width 0.1)
				(type default)
			)
			(layer "B.Fab")
		)
		(fp_line
			(start 0.12065 0.2794)
			(end 0.12065 0.3048)
			(stroke
				(width 0.1)
				(type default)
			)
			(layer "B.Fab")
		)
		(fp_line
			(start 0.12065 0.3048)
			(end 0.67945 0.3048)
			(stroke
				(width 0.1)
				(type default)
			)
			(layer "B.Fab")
		)
		(fp_line
			(start 0.67945 -0.305054)
			(end 0.12065 -0.305054)
			(stroke
				(width 0.1)
				(type default)
			)
			(layer "B.Fab")
		)
		(fp_line
			(start 0.67945 0.3048)
			(end 0.67945 -0.305054)
			(stroke
				(width 0.1)
				(type default)
			)
			(layer "B.Fab")
		)
		(pad "1" smd circle
			(at 0.40005 0 180)
			(size 0 0)
			(layers "B.Cu" "B.Mask" "B.Paste")
			(net "PVDDCR_SOC_P1")
		)
		(pad "2" smd circle
			(at -0.40005 0 180)
			(size 0 0)
			(layers "B.Cu" "B.Mask" "B.Paste")
			(net "GND")
		)
	)
	(footprint ""
		(layer "B.Cu")
		(at 169.66692 -52.415948 180)
		(property "Reference" "C1924"
			(at 0 0 0)
			(layer "B.SilkS")
			(hide yes)
			(effects
				(font
					(size 1.27 1.27)
				)
				(justify mirror)
			)
		)
		(property "Value" ""
			(at 0 0 0)
			(layer "B.Fab")
			(effects
				(font
					(size 1.27 1.27)
				)
				(justify mirror)
			)
		)
		(duplicate_pad_numbers_are_jumpers no)
		(fp_line
			(start 0.7874 0.4064)
			(end 0.7874 -0.4064)
			(stroke
				(width 0.1524)
				(type default)
			)
			(layer "B.SilkS")
		)
		(fp_line
			(start 0.7874 -0.4064)
			(end -0.7874 -0.4064)
			(stroke
				(width 0.1524)
				(type default)
			)
			(layer "B.SilkS")
		)
		(fp_line
			(start -0.7874 0.4064)
			(end 0.7874 0.4064)
			(stroke
				(width 0.1524)
				(type default)
			)
			(layer "B.SilkS")
		)
		(fp_line
			(start -0.7874 -0.4064)
			(end -0.7874 0.4064)
			(stroke
				(width 0.1524)
				(type default)
			)
			(layer "B.SilkS")
		)
		(fp_line
			(start 0.67945 0.3048)
			(end 0.67945 -0.305054)
			(stroke
				(width 0.1)
				(type default)
			)
			(layer "B.Fab")
		)
		(fp_line
			(start 0.67945 -0.305054)
			(end 0.12065 -0.305054)
			(stroke
				(width 0.1)
				(type default)
			)
			(layer "B.Fab")
		)
		(fp_line
			(start 0.12065 0.3048)
			(end 0.67945 0.3048)
			(stroke
				(width 0.1)
				(type default)
			)
			(layer "B.Fab")
		)
		(fp_line
			(start 0.12065 0.2794)
			(end 0.12065 0.3048)
			(stroke
				(width 0.1)
				(type default)
			)
			(layer "B.Fab")
		)
		(fp_line
			(start 0.12065 -0.2794)
			(end -0.12065 -0.2794)
			(stroke
				(width 0.1)
				(type default)
			)
			(layer "B.Fab")
		)
		(fp_line
			(start 0.12065 -0.305054)
			(end 0.12065 -0.2794)
			(stroke
				(width 0.1)
				(type default)
			)
			(layer "B.Fab")
		)
		(fp_line
			(start -0.120396 0.3048)
			(end -0.120396 0.2794)
			(stroke
				(width 0.1)
				(type default)
			)
			(layer "B.Fab")
		)
		(fp_line
			(start -0.120396 0.2794)
			(end 0.12065 0.2794)
			(stroke
				(width 0.1)
				(type default)
			)
			(layer "B.Fab")
		)
		(fp_line
			(start -0.12065 -0.2794)
			(end -0.12065 -0.3048)
			(stroke
				(width 0.1)
				(type default)
			)
			(layer "B.Fab")
		)
		(fp_line
			(start -0.12065 -0.3048)
			(end -0.67945 -0.3048)
			(stroke
				(width 0.1)
				(type default)
			)
			(layer "B.Fab")
		)
		(fp_line
			(start -0.67945 0.3048)
			(end -0.120396 0.3048)
			(stroke
				(width 0.1)
				(type default)
			)
			(layer "B.Fab")
		)
		(fp_line
			(start -0.67945 -0.3048)
			(end -0.67945 0.3048)
			(stroke
				(width 0.1)
				(type default)
			)
			(layer "B.Fab")
		)
		(pad "1" smd circle
			(at 0.40005 0)
			(size 0 0)
			(layers "B.Cu" "B.Mask" "B.Paste")
			(net "P3V3_M2_0")
		)
		(pad "2" smd circle
			(at -0.40005 0)
			(size 0 0)
			(layers "B.Cu" "B.Mask" "B.Paste")
			(net "GND")
		)
	)
)
